FILE_TYPE = MACRO_DRAWING;
SET COLOR_WIRE YELLOW;
SET COLOR_PROP MONO;
SET COLOR_DOT WHITE;
SET COLOR_ARC YELLOW;
SET COLOR_BODY GREEN;
SET COLOR_NOTE MONO;
SET PROP_DISPLAY VALUE;
SET PAGE_NUMBER P4;
FORCEADD INTEL_CORP_BPAGE..3
(0 0);
FORCEPROP 1 LAST CDS_CON_LAST_MODIFIED Fri Jun 16 17:47:56 2017
J 0
(-1425 325);
PAINT ORANGE (-1425 325);
DISPLAY INVISIBLE (-1425 325);
FORCEPROP 2 LAST CUSTOM_TXT_CDS <XR_PAGE_TITLE>
J 0
(-7890 5250);
DISPLAY 0.638298 (-7890 5250);
PAINT PINK (-7890 5250);
DISPLAY INVISIBLE (-7890 5250);
FORCEPROP 1 LAST CUSTOM_TXT_CDS <CON_TC_SNM7>
J 0
(-7050 3925);
PAINT ORANGE (-7050 3925);
FORCEPROP 1 LAST CUSTOM_TXT_CDS <CON_TC_SNM11>
J 0
(-7050 3525);
PAINT ORANGE (-7050 3525);
FORCEPROP 1 LAST CUSTOM_TXT_CDS <CON_TC_SNM9>
J 0
(-7050 3725);
PAINT ORANGE (-7050 3725);
FORCEPROP 1 LAST CUSTOM_TXT_CDS <CON_TC_SNO4>
J 2
(-7150 4225);
PAINT ORANGE (-7150 4225);
FORCEPROP 1 LAST CUSTOM_TXT_CDS <CON_TC_SNM5>
J 0
(-7050 4125);
PAINT ORANGE (-7050 4125);
FORCEPROP 1 LAST CUSTOM_TXT_CDS <CON_TC_SNM2>
J 0
(-7050 4425);
PAINT ORANGE (-7050 4425);
FORCEPROP 1 LAST CUSTOM_TXT_CDS <CON_TC_SNO19>
J 2
(-7150 2725);
PAINT ORANGE (-7150 2725);
FORCEPROP 1 LAST CUSTOM_TXT_CDS <CON_TC_SNM3>
J 0
(-7050 4325);
PAINT ORANGE (-7050 4325);
FORCEPROP 1 LAST CUSTOM_TXT_CDS <CON_TC_SNM14>
J 0
(-7050 3225);
PAINT ORANGE (-7050 3225);
FORCEPROP 1 LAST CUSTOM_TXT_CDS <CON_TC_SNM4>
J 0
(-7050 4225);
PAINT ORANGE (-7050 4225);
FORCEPROP 1 LAST CUSTOM_TXT_CDS <CON_TC_SNO3>
J 2
(-7150 4325);
PAINT ORANGE (-7150 4325);
FORCEPROP 1 LAST CUSTOM_TXT_CDS <CON_TC_SNM6>
J 0
(-7050 4025);
PAINT ORANGE (-7050 4025);
FORCEPROP 1 LAST CUSTOM_TXT_CDS <CON_TC_SNO1>
J 2
(-7150 4525);
PAINT ORANGE (-7150 4525);
FORCEPROP 1 LAST CUSTOM_TXT_CDS <CON_TC_SNO2>
J 2
(-7150 4425);
PAINT ORANGE (-7150 4425);
FORCEPROP 2 LAST CUSTOM_TXT_CDS <CON_LAST_MODIFIED>
J 0
(-4000 100);
PAINT ORANGE (-4000 100);
FORCEPROP 1 LAST CUSTOM_TXT_CDS <CON_TC_SNM8>
J 0
(-7050 3825);
PAINT ORANGE (-7050 3825);
FORCEPROP 1 LAST CUSTOM_TXT_CDS <CON_TC_SNM15>
J 0
(-7050 3125);
PAINT ORANGE (-7050 3125);
FORCEPROP 1 LAST CUSTOM_TXT_CDS <CON_TC_SNM10>
J 0
(-7050 3625);
PAINT ORANGE (-7050 3625);
FORCEPROP 1 LAST CUSTOM_TXT_CDS <CURRENT_DESIGN_SHEET> OF <TOTAL_DESIGN_SHEETS>
J 0
(-500 25);
PAINT ORANGE (-500 25);
FORCEPROP 1 LAST CUSTOM_TXT_CDS <CON_TC_SNM1>
J 0
(-7050 4525);
PAINT ORANGE (-7050 4525);
FORCEPROP 1 LAST CUSTOM_TXT_CDS <CON_TC_SNM12>
J 0
(-7050 3425);
PAINT ORANGE (-7050 3425);
FORCEPROP 1 LAST CUSTOM_TXT_CDS <CON_TC_SNM13>
J 0
(-7050 3325);
PAINT ORANGE (-7050 3325);
FORCEPROP 1 LAST CUSTOM_TXT_CDS <CON_TC_SNM16>
J 0
(-7050 3025);
PAINT ORANGE (-7050 3025);
FORCEPROP 1 LAST CUSTOM_TXT_CDS <CON_TC_SNM17>
J 0
(-7050 2925);
PAINT ORANGE (-7050 2925);
FORCEPROP 1 LAST CUSTOM_TXT_CDS <CON_TC_SNM18>
J 0
(-7050 2825);
PAINT ORANGE (-7050 2825);
FORCEPROP 1 LAST CUSTOM_TXT_CDS <CON_TC_SNM19>
J 0
(-7050 2725);
PAINT ORANGE (-7050 2725);
FORCEPROP 1 LAST CUSTOM_TXT_CDS <CON_TC_SNM20>
J 0
(-7050 2625);
PAINT ORANGE (-7050 2625);
FORCEPROP 1 LAST CUSTOM_TXT_CDS <CON_TC_SNM21>
J 0
(-7050 2525);
PAINT ORANGE (-7050 2525);
FORCEPROP 1 LAST CUSTOM_TXT_CDS <CON_TC_SNM22>
J 0
(-7050 2425);
PAINT ORANGE (-7050 2425);
FORCEPROP 1 LAST CUSTOM_TXT_CDS <CON_TC_SNM23>
J 0
(-7050 2325);
PAINT ORANGE (-7050 2325);
FORCEPROP 1 LAST CUSTOM_TXT_CDS <CON_TC_SNM24>
J 0
(-7050 2225);
PAINT ORANGE (-7050 2225);
FORCEPROP 1 LAST CUSTOM_TXT_CDS <CON_TC_SNM25>
J 0
(-7050 2125);
PAINT ORANGE (-7050 2125);
FORCEPROP 1 LAST CUSTOM_TXT_CDS <CON_TC_SNM26>
J 0
(-7050 2025);
PAINT ORANGE (-7050 2025);
FORCEPROP 1 LAST CUSTOM_TXT_CDS <CON_TC_SNM27>
J 0
(-7050 1925);
PAINT ORANGE (-7050 1925);
FORCEPROP 1 LAST CUSTOM_TXT_CDS <CON_TC_SNM28>
J 0
(-7050 1825);
PAINT ORANGE (-7050 1825);
FORCEPROP 1 LAST CUSTOM_TXT_CDS <CON_TC_SNM29>
J 0
(-7050 1725);
PAINT ORANGE (-7050 1725);
FORCEPROP 1 LAST CUSTOM_TXT_CDS <CON_TC_SNM30>
J 0
(-7050 1625);
PAINT ORANGE (-7050 1625);
FORCEPROP 1 LAST CUSTOM_TXT_CDS <CON_TC_SNM31>
J 0
(-7050 1525);
PAINT ORANGE (-7050 1525);
FORCEPROP 1 LAST CUSTOM_TXT_CDS <CON_TC_SNM32>
J 0
(-7050 1425);
PAINT ORANGE (-7050 1425);
FORCEPROP 1 LAST CUSTOM_TXT_CDS <CON_TC_SNM33>
J 0
(-7050 1325);
PAINT ORANGE (-7050 1325);
FORCEPROP 1 LAST CUSTOM_TXT_CDS <CON_TC_SNM34>
J 0
(-7050 1225);
PAINT ORANGE (-7050 1225);
FORCEPROP 1 LAST CUSTOM_TXT_CDS <CON_TC_SNM35>
J 0
(-7050 1125);
PAINT ORANGE (-7050 1125);
FORCEPROP 1 LAST CUSTOM_TXT_CDS <CON_TC_SNM36>
J 0
(-7050 1025);
PAINT ORANGE (-7050 1025);
FORCEPROP 1 LAST CUSTOM_TXT_CDS <CON_TC_SNM37>
J 0
(-7050 925);
PAINT ORANGE (-7050 925);
FORCEPROP 1 LAST CUSTOM_TXT_CDS <CON_TC_SNM38>
J 0
(-7050 825);
PAINT ORANGE (-7050 825);
FORCEPROP 1 LAST CUSTOM_TXT_CDS <CON_TC_SNM39>
J 0
(-7050 725);
PAINT ORANGE (-7050 725);
FORCEPROP 1 LAST CUSTOM_TXT_CDS <CON_TC_SNM40>
J 0
(-7050 625);
PAINT ORANGE (-7050 625);
FORCEPROP 1 LAST CUSTOM_TXT_CDS <CON_TC_SNM41>
J 0
(-4550 4525);
PAINT ORANGE (-4550 4525);
FORCEPROP 1 LAST CUSTOM_TXT_CDS <CON_TC_SNM42>
J 0
(-4550 4425);
PAINT ORANGE (-4550 4425);
FORCEPROP 1 LAST CUSTOM_TXT_CDS <CON_TC_SNM43>
J 0
(-4550 4325);
PAINT ORANGE (-4550 4325);
FORCEPROP 1 LAST CUSTOM_TXT_CDS <CON_TC_SNM44>
J 0
(-4550 4225);
PAINT ORANGE (-4550 4225);
FORCEPROP 1 LAST CUSTOM_TXT_CDS <CON_TC_SNM45>
J 0
(-4550 4125);
PAINT ORANGE (-4550 4125);
FORCEPROP 1 LAST CUSTOM_TXT_CDS <CON_TC_SNM46>
J 0
(-4550 4025);
PAINT ORANGE (-4550 4025);
FORCEPROP 1 LAST CUSTOM_TXT_CDS <CON_TC_SNM47>
J 0
(-4550 3925);
PAINT ORANGE (-4550 3925);
FORCEPROP 1 LAST CUSTOM_TXT_CDS <CON_TC_SNM48>
J 0
(-4550 3825);
PAINT ORANGE (-4550 3825);
FORCEPROP 1 LAST CUSTOM_TXT_CDS <CON_TC_SNM49>
J 0
(-4550 3725);
PAINT ORANGE (-4550 3725);
FORCEPROP 1 LAST CUSTOM_TXT_CDS <CON_TC_SNM50>
J 0
(-4550 3625);
PAINT ORANGE (-4550 3625);
FORCEPROP 1 LAST CUSTOM_TXT_CDS <CON_TC_SNM51>
J 0
(-4550 3525);
PAINT ORANGE (-4550 3525);
FORCEPROP 1 LAST CUSTOM_TXT_CDS <CON_TC_SNM52>
J 0
(-4550 3425);
PAINT ORANGE (-4550 3425);
FORCEPROP 1 LAST CUSTOM_TXT_CDS <CON_TC_SNM53>
J 0
(-4550 3325);
PAINT ORANGE (-4550 3325);
FORCEPROP 1 LAST CUSTOM_TXT_CDS <CON_TC_SNM54>
J 0
(-4550 3225);
PAINT ORANGE (-4550 3225);
FORCEPROP 1 LAST CUSTOM_TXT_CDS <CON_TC_SNM55>
J 0
(-4550 3125);
PAINT ORANGE (-4550 3125);
FORCEPROP 1 LAST CUSTOM_TXT_CDS <CON_TC_SNM56>
J 0
(-4550 3025);
PAINT ORANGE (-4550 3025);
FORCEPROP 1 LAST CUSTOM_TXT_CDS <CON_TC_SNM57>
J 0
(-4550 2925);
PAINT ORANGE (-4550 2925);
FORCEPROP 1 LAST CUSTOM_TXT_CDS <CON_TC_SNM58>
J 0
(-4550 2825);
PAINT ORANGE (-4550 2825);
FORCEPROP 1 LAST CUSTOM_TXT_CDS <CON_TC_SNM59>
J 0
(-4550 2725);
PAINT ORANGE (-4550 2725);
FORCEPROP 1 LAST CUSTOM_TXT_CDS <CON_TC_SNM60>
J 0
(-4550 2625);
PAINT ORANGE (-4550 2625);
FORCEPROP 1 LAST CUSTOM_TXT_CDS <CON_TC_SNM61>
J 0
(-4550 2525);
PAINT ORANGE (-4550 2525);
FORCEPROP 1 LAST CUSTOM_TXT_CDS <CON_TC_SNM62>
J 0
(-4550 2425);
PAINT ORANGE (-4550 2425);
FORCEPROP 1 LAST CUSTOM_TXT_CDS <CON_TC_SNM63>
J 0
(-4550 2325);
PAINT ORANGE (-4550 2325);
FORCEPROP 1 LAST CUSTOM_TXT_CDS <CON_TC_SNM64>
J 0
(-4550 2225);
PAINT ORANGE (-4550 2225);
FORCEPROP 1 LAST CUSTOM_TXT_CDS <CON_TC_SNM65>
J 0
(-4550 2125);
PAINT ORANGE (-4550 2125);
FORCEPROP 1 LAST CUSTOM_TXT_CDS <CON_TC_SNM66>
J 0
(-4550 2025);
PAINT ORANGE (-4550 2025);
FORCEPROP 1 LAST CUSTOM_TXT_CDS <CON_TC_SNM67>
J 0
(-4550 1925);
PAINT ORANGE (-4550 1925);
FORCEPROP 1 LAST CUSTOM_TXT_CDS <CON_TC_SNM68>
J 0
(-4550 1825);
PAINT ORANGE (-4550 1825);
FORCEPROP 1 LAST CUSTOM_TXT_CDS <CON_TC_SNM69>
J 0
(-4550 1725);
PAINT ORANGE (-4550 1725);
FORCEPROP 1 LAST CUSTOM_TXT_CDS <CON_TC_SNM70>
J 0
(-4550 1625);
PAINT ORANGE (-4550 1625);
FORCEPROP 1 LAST CUSTOM_TXT_CDS <CON_TC_SNM71>
J 0
(-4550 1525);
PAINT ORANGE (-4550 1525);
FORCEPROP 1 LAST CUSTOM_TXT_CDS <CON_TC_SNM72>
J 0
(-4550 1425);
PAINT ORANGE (-4550 1425);
FORCEPROP 1 LAST CUSTOM_TXT_CDS <CON_TC_SNM73>
J 0
(-4550 1325);
PAINT ORANGE (-4550 1325);
FORCEPROP 1 LAST CUSTOM_TXT_CDS <CON_TC_SNM74>
J 0
(-4550 1225);
PAINT ORANGE (-4550 1225);
FORCEPROP 1 LAST CUSTOM_TXT_CDS <CON_TC_SNM75>
J 0
(-4550 1125);
PAINT ORANGE (-4550 1125);
FORCEPROP 1 LAST CUSTOM_TXT_CDS <CON_TC_SNM76>
J 0
(-4550 1025);
PAINT ORANGE (-4550 1025);
FORCEPROP 1 LAST CUSTOM_TXT_CDS <CON_TC_SNM77>
J 0
(-4550 925);
PAINT ORANGE (-4550 925);
FORCEPROP 1 LAST CUSTOM_TXT_CDS <CON_TC_SNM78>
J 0
(-4550 825);
PAINT ORANGE (-4550 825);
FORCEPROP 1 LAST CUSTOM_TXT_CDS <CON_TC_SNM79>
J 0
(-4550 725);
PAINT ORANGE (-4550 725);
FORCEPROP 1 LAST CUSTOM_TXT_CDS <CON_TC_SNM80>
J 0
(-4550 625);
PAINT ORANGE (-4550 625);
FORCEPROP 1 LAST CUSTOM_TXT_CDS <CON_TC_SNM81>
J 0
(-2050 4525);
PAINT ORANGE (-2050 4525);
FORCEPROP 1 LAST CUSTOM_TXT_CDS <CON_TC_SNM82>
J 0
(-2050 4425);
PAINT ORANGE (-2050 4425);
FORCEPROP 1 LAST CUSTOM_TXT_CDS <CON_TC_SNM83>
J 0
(-2050 4325);
PAINT ORANGE (-2050 4325);
FORCEPROP 1 LAST CUSTOM_TXT_CDS <CON_TC_SNM84>
J 0
(-2050 4225);
PAINT ORANGE (-2050 4225);
FORCEPROP 1 LAST CUSTOM_TXT_CDS <CON_TC_SNM85>
J 0
(-2050 4125);
PAINT ORANGE (-2050 4125);
FORCEPROP 1 LAST CUSTOM_TXT_CDS <CON_TC_SNM86>
J 0
(-2050 4025);
PAINT ORANGE (-2050 4025);
FORCEPROP 1 LAST CUSTOM_TXT_CDS <CON_TC_SNM87>
J 0
(-2050 3925);
PAINT ORANGE (-2050 3925);
FORCEPROP 1 LAST CUSTOM_TXT_CDS <CON_TC_SNM88>
J 0
(-2050 3825);
PAINT ORANGE (-2050 3825);
FORCEPROP 1 LAST CUSTOM_TXT_CDS <CON_TC_SNM89>
J 0
(-2050 3725);
PAINT ORANGE (-2050 3725);
FORCEPROP 1 LAST CUSTOM_TXT_CDS <CON_TC_SNM90>
J 0
(-2050 3625);
PAINT ORANGE (-2050 3625);
FORCEPROP 1 LAST CUSTOM_TXT_CDS <CON_TC_SNM91>
J 0
(-2050 3525);
PAINT ORANGE (-2050 3525);
FORCEPROP 1 LAST CUSTOM_TXT_CDS <CON_TC_SNM92>
J 0
(-2050 3425);
PAINT ORANGE (-2050 3425);
FORCEPROP 1 LAST CUSTOM_TXT_CDS <CON_TC_SNM93>
J 0
(-2050 3325);
PAINT ORANGE (-2050 3325);
FORCEPROP 1 LAST CUSTOM_TXT_CDS <CON_TC_SNM94>
J 0
(-2050 3225);
PAINT ORANGE (-2050 3225);
FORCEPROP 1 LAST CUSTOM_TXT_CDS <CON_TC_SNM95>
J 0
(-2050 3125);
PAINT ORANGE (-2050 3125);
FORCEPROP 1 LAST CUSTOM_TXT_CDS <CON_TC_SNM96>
J 0
(-2050 3025);
PAINT ORANGE (-2050 3025);
FORCEPROP 1 LAST CUSTOM_TXT_CDS <CON_TC_SNM97>
J 0
(-2050 2925);
PAINT ORANGE (-2050 2925);
FORCEPROP 1 LAST CUSTOM_TXT_CDS <CON_TC_SNM98>
J 0
(-2050 2825);
PAINT ORANGE (-2050 2825);
FORCEPROP 1 LAST CUSTOM_TXT_CDS <CON_TC_SNM99>
J 0
(-2050 2725);
PAINT ORANGE (-2050 2725);
FORCEPROP 1 LAST CUSTOM_TXT_CDS <CON_TC_SNM100>
J 0
(-2050 2625);
PAINT ORANGE (-2050 2625);
FORCEPROP 1 LAST CUSTOM_TXT_CDS <CON_TC_SNM101>
J 0
(-2050 2525);
PAINT ORANGE (-2050 2525);
FORCEPROP 1 LAST CUSTOM_TXT_CDS <CON_TC_SNM102>
J 0
(-2050 2425);
PAINT ORANGE (-2050 2425);
FORCEPROP 1 LAST CUSTOM_TXT_CDS <CON_TC_SNM103>
J 0
(-2050 2325);
PAINT ORANGE (-2050 2325);
FORCEPROP 1 LAST CUSTOM_TXT_CDS <CON_TC_SNM104>
J 0
(-2050 2225);
PAINT ORANGE (-2050 2225);
FORCEPROP 1 LAST CUSTOM_TXT_CDS <CON_TC_SNM105>
J 0
(-2050 2125);
PAINT ORANGE (-2050 2125);
FORCEPROP 1 LAST CUSTOM_TXT_CDS <CON_TC_SNM106>
J 0
(-2050 2025);
PAINT ORANGE (-2050 2025);
FORCEPROP 1 LAST CUSTOM_TXT_CDS <CON_TC_SNM107>
J 0
(-2050 1925);
PAINT ORANGE (-2050 1925);
FORCEPROP 1 LAST CUSTOM_TXT_CDS <CON_TC_SNM108>
J 0
(-2050 1825);
PAINT ORANGE (-2050 1825);
FORCEPROP 1 LAST CUSTOM_TXT_CDS <CON_TC_SNM109>
J 0
(-2050 1725);
PAINT ORANGE (-2050 1725);
FORCEPROP 1 LAST CUSTOM_TXT_CDS <CON_TC_SNM110>
J 0
(-2050 1625);
PAINT ORANGE (-2050 1625);
FORCEPROP 1 LAST CUSTOM_TXT_CDS <CON_TC_SNM111>
J 0
(-2050 1525);
PAINT ORANGE (-2050 1525);
FORCEPROP 1 LAST CUSTOM_TXT_CDS <CON_TC_SNM112>
J 0
(-2050 1425);
PAINT ORANGE (-2050 1425);
FORCEPROP 1 LAST CUSTOM_TXT_CDS <CON_TC_SNM113>
J 0
(-2050 1325);
PAINT ORANGE (-2050 1325);
FORCEPROP 1 LAST CUSTOM_TXT_CDS <CON_TC_SNM114>
J 0
(-2050 1225);
PAINT ORANGE (-2050 1225);
FORCEPROP 1 LAST CUSTOM_TXT_CDS <CON_TC_SNM115>
J 0
(-2050 1125);
PAINT ORANGE (-2050 1125);
FORCEPROP 1 LAST CUSTOM_TXT_CDS <CON_TC_SNM116>
J 0
(-2050 1025);
PAINT ORANGE (-2050 1025);
FORCEPROP 1 LAST CUSTOM_TXT_CDS <CON_TC_SNM117>
J 0
(-2050 925);
PAINT ORANGE (-2050 925);
FORCEPROP 1 LAST CUSTOM_TXT_CDS <CON_TC_SNM118>
J 0
(-2050 825);
PAINT ORANGE (-2050 825);
FORCEPROP 1 LAST CUSTOM_TXT_CDS <CON_TC_SNM119>
J 0
(-2050 725);
PAINT ORANGE (-2050 725);
FORCEPROP 1 LAST CUSTOM_TXT_CDS <CON_TC_SNM120>
J 0
(-2050 625);
PAINT ORANGE (-2050 625);
FORCEPROP 1 LAST CUSTOM_TXT_CDS <CON_TC_SNO5>
J 2
(-7150 4125);
PAINT ORANGE (-7150 4125);
FORCEPROP 1 LAST CUSTOM_TXT_CDS <CON_TC_SNO6>
J 2
(-7150 4025);
PAINT ORANGE (-7150 4025);
FORCEPROP 1 LAST CUSTOM_TXT_CDS <CON_TC_SNO7>
J 2
(-7150 3925);
PAINT ORANGE (-7150 3925);
FORCEPROP 1 LAST CUSTOM_TXT_CDS <CON_TC_SNO8>
J 2
(-7150 3825);
PAINT ORANGE (-7150 3825);
FORCEPROP 1 LAST CUSTOM_TXT_CDS <CON_TC_SNO9>
J 2
(-7150 3725);
PAINT ORANGE (-7150 3725);
FORCEPROP 1 LAST CUSTOM_TXT_CDS <CON_TC_SNO10>
J 2
(-7150 3625);
PAINT ORANGE (-7150 3625);
FORCEPROP 1 LAST CUSTOM_TXT_CDS <CON_TC_SNO11>
J 2
(-7150 3525);
PAINT ORANGE (-7150 3525);
FORCEPROP 1 LAST CUSTOM_TXT_CDS <CON_TC_SNO12>
J 2
(-7150 3425);
PAINT ORANGE (-7150 3425);
FORCEPROP 1 LAST CUSTOM_TXT_CDS <CON_TC_SNO13>
J 2
(-7150 3325);
PAINT ORANGE (-7150 3325);
FORCEPROP 1 LAST CUSTOM_TXT_CDS <CON_TC_SNO14>
J 2
(-7150 3225);
PAINT ORANGE (-7150 3225);
FORCEPROP 1 LAST CUSTOM_TXT_CDS <CON_TC_SNO15>
J 2
(-7150 3125);
PAINT ORANGE (-7150 3125);
FORCEPROP 1 LAST CUSTOM_TXT_CDS <CON_TC_SNO16>
J 2
(-7150 3025);
PAINT ORANGE (-7150 3025);
FORCEPROP 1 LAST CUSTOM_TXT_CDS <CON_TC_SNO17>
J 2
(-7150 2925);
PAINT ORANGE (-7150 2925);
FORCEPROP 1 LAST CUSTOM_TXT_CDS <CON_TC_SNO18>
J 2
(-7150 2825);
PAINT ORANGE (-7150 2825);
FORCEPROP 1 LAST CUSTOM_TXT_CDS <CON_TC_SNO20>
J 2
(-7150 2625);
PAINT ORANGE (-7150 2625);
FORCEPROP 1 LAST CUSTOM_TXT_CDS <CON_TC_SNO21>
J 2
(-7150 2525);
PAINT ORANGE (-7150 2525);
FORCEPROP 1 LAST CUSTOM_TXT_CDS <CON_TC_SNO22>
J 2
(-7150 2425);
PAINT ORANGE (-7150 2425);
FORCEPROP 1 LAST CUSTOM_TXT_CDS <CON_TC_SNO23>
J 2
(-7150 2325);
PAINT ORANGE (-7150 2325);
FORCEPROP 1 LAST CUSTOM_TXT_CDS <CON_TC_SNO24>
J 2
(-7150 2225);
PAINT ORANGE (-7150 2225);
FORCEPROP 1 LAST CUSTOM_TXT_CDS <CON_TC_SNO25>
J 2
(-7150 2125);
PAINT ORANGE (-7150 2125);
FORCEPROP 1 LAST CUSTOM_TXT_CDS <CON_TC_SNO26>
J 2
(-7150 2025);
PAINT ORANGE (-7150 2025);
FORCEPROP 1 LAST CUSTOM_TXT_CDS <CON_TC_SNO27>
J 2
(-7150 1925);
PAINT ORANGE (-7150 1925);
FORCEPROP 1 LAST CUSTOM_TXT_CDS <CON_TC_SNO28>
J 2
(-7150 1825);
PAINT ORANGE (-7150 1825);
FORCEPROP 1 LAST CUSTOM_TXT_CDS <CON_TC_SNO29>
J 2
(-7150 1725);
PAINT ORANGE (-7150 1725);
FORCEPROP 1 LAST CUSTOM_TXT_CDS <CON_TC_SNO30>
J 2
(-7150 1625);
PAINT ORANGE (-7150 1625);
FORCEPROP 1 LAST CUSTOM_TXT_CDS <CON_TC_SNO31>
J 2
(-7150 1525);
PAINT ORANGE (-7150 1525);
FORCEPROP 1 LAST CUSTOM_TXT_CDS <CON_TC_SNO32>
J 2
(-7150 1425);
PAINT ORANGE (-7150 1425);
FORCEPROP 1 LAST CUSTOM_TXT_CDS <CON_TC_SNO33>
J 2
(-7150 1325);
PAINT ORANGE (-7150 1325);
FORCEPROP 1 LAST CUSTOM_TXT_CDS <CON_TC_SNO34>
J 2
(-7150 1225);
PAINT ORANGE (-7150 1225);
FORCEPROP 1 LAST CUSTOM_TXT_CDS <CON_TC_SNO35>
J 2
(-7150 1125);
PAINT ORANGE (-7150 1125);
FORCEPROP 1 LAST CUSTOM_TXT_CDS <CON_TC_SNO36>
J 2
(-7150 1025);
PAINT ORANGE (-7150 1025);
FORCEPROP 1 LAST CUSTOM_TXT_CDS <CON_TC_SNO37>
J 2
(-7150 925);
PAINT ORANGE (-7150 925);
FORCEPROP 1 LAST CUSTOM_TXT_CDS <CON_TC_SNO38>
J 2
(-7150 825);
PAINT ORANGE (-7150 825);
FORCEPROP 1 LAST CUSTOM_TXT_CDS <CON_TC_SNO39>
J 2
(-7150 725);
PAINT ORANGE (-7150 725);
FORCEPROP 1 LAST CUSTOM_TXT_CDS <CON_TC_SNO40>
J 2
(-7150 625);
PAINT ORANGE (-7150 625);
FORCEPROP 1 LAST CUSTOM_TXT_CDS <CON_TC_SNO41>
J 2
(-4650 4525);
PAINT ORANGE (-4650 4525);
FORCEPROP 1 LAST CUSTOM_TXT_CDS <CON_TC_SNO42>
J 2
(-4650 4425);
PAINT ORANGE (-4650 4425);
FORCEPROP 1 LAST CUSTOM_TXT_CDS <CON_TC_SNO43>
J 2
(-4650 4325);
PAINT ORANGE (-4650 4325);
FORCEPROP 1 LAST CUSTOM_TXT_CDS <CON_TC_SNO44>
J 2
(-4650 4225);
PAINT ORANGE (-4650 4225);
FORCEPROP 1 LAST CUSTOM_TXT_CDS <CON_TC_SNO45>
J 2
(-4650 4125);
PAINT ORANGE (-4650 4125);
FORCEPROP 1 LAST CUSTOM_TXT_CDS <CON_TC_SNO46>
J 2
(-4650 4025);
PAINT ORANGE (-4650 4025);
FORCEPROP 1 LAST CUSTOM_TXT_CDS <CON_TC_SNO47>
J 2
(-4650 3925);
PAINT ORANGE (-4650 3925);
FORCEPROP 1 LAST CUSTOM_TXT_CDS <CON_TC_SNO48>
J 2
(-4650 3825);
PAINT ORANGE (-4650 3825);
FORCEPROP 1 LAST CUSTOM_TXT_CDS <CON_TC_SNO49>
J 2
(-4650 3725);
PAINT ORANGE (-4650 3725);
FORCEPROP 1 LAST CUSTOM_TXT_CDS <CON_TC_SNO50>
J 2
(-4650 3625);
PAINT ORANGE (-4650 3625);
FORCEPROP 1 LAST CUSTOM_TXT_CDS <CON_TC_SNO51>
J 2
(-4650 3525);
PAINT ORANGE (-4650 3525);
FORCEPROP 1 LAST CUSTOM_TXT_CDS <CON_TC_SNO52>
J 2
(-4650 3425);
PAINT ORANGE (-4650 3425);
FORCEPROP 1 LAST CUSTOM_TXT_CDS <CON_TC_SNO53>
J 2
(-4650 3325);
PAINT ORANGE (-4650 3325);
FORCEPROP 1 LAST CUSTOM_TXT_CDS <CON_TC_SNO54>
J 2
(-4650 3225);
PAINT ORANGE (-4650 3225);
FORCEPROP 1 LAST CUSTOM_TXT_CDS <CON_TC_SNO55>
J 2
(-4650 3125);
PAINT ORANGE (-4650 3125);
FORCEPROP 1 LAST CUSTOM_TXT_CDS <CON_TC_SNO56>
J 2
(-4650 3025);
PAINT ORANGE (-4650 3025);
FORCEPROP 1 LAST CUSTOM_TXT_CDS <CON_TC_SNO57>
J 2
(-4650 2925);
PAINT ORANGE (-4650 2925);
FORCEPROP 1 LAST CUSTOM_TXT_CDS <CON_TC_SNO58>
J 2
(-4650 2825);
PAINT ORANGE (-4650 2825);
FORCEPROP 1 LAST CUSTOM_TXT_CDS <CON_TC_SNO59>
J 2
(-4650 2725);
PAINT ORANGE (-4650 2725);
FORCEPROP 1 LAST CUSTOM_TXT_CDS <CON_TC_SNO60>
J 2
(-4650 2625);
PAINT ORANGE (-4650 2625);
FORCEPROP 1 LAST CUSTOM_TXT_CDS <CON_TC_SNO61>
J 2
(-4650 2525);
PAINT ORANGE (-4650 2525);
FORCEPROP 1 LAST CUSTOM_TXT_CDS <CON_TC_SNO62>
J 2
(-4650 2425);
PAINT ORANGE (-4650 2425);
FORCEPROP 1 LAST CUSTOM_TXT_CDS <CON_TC_SNO63>
J 2
(-4650 2325);
PAINT ORANGE (-4650 2325);
FORCEPROP 1 LAST CUSTOM_TXT_CDS <CON_TC_SNO64>
J 2
(-4650 2225);
PAINT ORANGE (-4650 2225);
FORCEPROP 1 LAST CUSTOM_TXT_CDS <CON_TC_SNO65>
J 2
(-4650 2125);
PAINT ORANGE (-4650 2125);
FORCEPROP 1 LAST CUSTOM_TXT_CDS <CON_TC_SNO66>
J 2
(-4650 2025);
PAINT ORANGE (-4650 2025);
FORCEPROP 1 LAST CUSTOM_TXT_CDS <CON_TC_SNO67>
J 2
(-4650 1925);
PAINT ORANGE (-4650 1925);
FORCEPROP 1 LAST CUSTOM_TXT_CDS <CON_TC_SNO68>
J 2
(-4650 1825);
PAINT ORANGE (-4650 1825);
FORCEPROP 1 LAST CUSTOM_TXT_CDS <CON_TC_SNO69>
J 2
(-4650 1725);
PAINT ORANGE (-4650 1725);
FORCEPROP 1 LAST CUSTOM_TXT_CDS <CON_TC_SNO70>
J 2
(-4650 1625);
PAINT ORANGE (-4650 1625);
FORCEPROP 1 LAST CUSTOM_TXT_CDS <CON_TC_SNO71>
J 2
(-4650 1525);
PAINT ORANGE (-4650 1525);
FORCEPROP 1 LAST CUSTOM_TXT_CDS <CON_TC_SNO72>
J 2
(-4650 1425);
PAINT ORANGE (-4650 1425);
FORCEPROP 1 LAST CUSTOM_TXT_CDS <CON_TC_SNO73>
J 2
(-4650 1325);
PAINT ORANGE (-4650 1325);
FORCEPROP 1 LAST CUSTOM_TXT_CDS <CON_TC_SNO74>
J 2
(-4650 1225);
PAINT ORANGE (-4650 1225);
FORCEPROP 1 LAST CUSTOM_TXT_CDS <CON_TC_SNO75>
J 2
(-4650 1125);
PAINT ORANGE (-4650 1125);
FORCEPROP 1 LAST CUSTOM_TXT_CDS <CON_TC_SNO76>
J 2
(-4650 1025);
PAINT ORANGE (-4650 1025);
FORCEPROP 1 LAST CUSTOM_TXT_CDS <CON_TC_SNO77>
J 2
(-4650 925);
PAINT ORANGE (-4650 925);
FORCEPROP 1 LAST CUSTOM_TXT_CDS <CON_TC_SNO78>
J 2
(-4650 825);
PAINT ORANGE (-4650 825);
FORCEPROP 1 LAST CUSTOM_TXT_CDS <CON_TC_SNO79>
J 2
(-4650 725);
PAINT ORANGE (-4650 725);
FORCEPROP 1 LAST CUSTOM_TXT_CDS <CON_TC_SNO80>
J 2
(-4650 625);
PAINT ORANGE (-4650 625);
FORCEPROP 1 LAST CUSTOM_TXT_CDS <CON_TC_SNO81>
J 2
(-2150 4525);
PAINT ORANGE (-2150 4525);
FORCEPROP 1 LAST CUSTOM_TXT_CDS <CON_TC_SNO82>
J 2
(-2150 4425);
PAINT ORANGE (-2150 4425);
FORCEPROP 1 LAST CUSTOM_TXT_CDS <CON_TC_SNO83>
J 2
(-2150 4325);
PAINT ORANGE (-2150 4325);
FORCEPROP 1 LAST CUSTOM_TXT_CDS <CON_TC_SNO84>
J 2
(-2150 4225);
PAINT ORANGE (-2150 4225);
FORCEPROP 1 LAST CUSTOM_TXT_CDS <CON_TC_SNO85>
J 2
(-2150 4125);
PAINT ORANGE (-2150 4125);
FORCEPROP 1 LAST CUSTOM_TXT_CDS <CON_TC_SNO86>
J 2
(-2150 4025);
PAINT ORANGE (-2150 4025);
FORCEPROP 1 LAST CUSTOM_TXT_CDS <CON_TC_SNO87>
J 2
(-2150 3925);
PAINT ORANGE (-2150 3925);
FORCEPROP 1 LAST CUSTOM_TXT_CDS <CON_TC_SNO88>
J 2
(-2150 3825);
PAINT ORANGE (-2150 3825);
FORCEPROP 1 LAST CUSTOM_TXT_CDS <CON_TC_SNO89>
J 2
(-2150 3725);
PAINT ORANGE (-2150 3725);
FORCEPROP 1 LAST CUSTOM_TXT_CDS <CON_TC_SNO90>
J 2
(-2150 3625);
PAINT ORANGE (-2150 3625);
FORCEPROP 1 LAST CUSTOM_TXT_CDS <CON_TC_SNO91>
J 2
(-2150 3525);
PAINT ORANGE (-2150 3525);
FORCEPROP 1 LAST CUSTOM_TXT_CDS <CON_TC_SNO92>
J 2
(-2150 3425);
PAINT ORANGE (-2150 3425);
FORCEPROP 1 LAST CUSTOM_TXT_CDS <CON_TC_SNO93>
J 2
(-2150 3325);
PAINT ORANGE (-2150 3325);
FORCEPROP 1 LAST CUSTOM_TXT_CDS <CON_TC_SNO94>
J 2
(-2150 3225);
PAINT ORANGE (-2150 3225);
FORCEPROP 1 LAST CUSTOM_TXT_CDS <CON_TC_SNO95>
J 2
(-2150 3125);
PAINT ORANGE (-2150 3125);
FORCEPROP 1 LAST CUSTOM_TXT_CDS <CON_TC_SNO96>
J 2
(-2150 3025);
PAINT ORANGE (-2150 3025);
FORCEPROP 1 LAST CUSTOM_TXT_CDS <CON_TC_SNO97>
J 2
(-2150 2925);
PAINT ORANGE (-2150 2925);
FORCEPROP 1 LAST CUSTOM_TXT_CDS <CON_TC_SNO98>
J 2
(-2150 2825);
PAINT ORANGE (-2150 2825);
FORCEPROP 1 LAST CUSTOM_TXT_CDS <CON_TC_SNO99>
J 2
(-2150 2725);
PAINT ORANGE (-2150 2725);
FORCEPROP 1 LAST CUSTOM_TXT_CDS <CON_TC_SNO100>
J 2
(-2150 2625);
PAINT ORANGE (-2150 2625);
FORCEPROP 1 LAST CUSTOM_TXT_CDS <CON_TC_SNO101>
J 2
(-2150 2525);
PAINT ORANGE (-2150 2525);
FORCEPROP 1 LAST CUSTOM_TXT_CDS <CON_TC_SNO102>
J 2
(-2150 2425);
PAINT ORANGE (-2150 2425);
FORCEPROP 1 LAST CUSTOM_TXT_CDS <CON_TC_SNO103>
J 2
(-2150 2325);
PAINT ORANGE (-2150 2325);
FORCEPROP 1 LAST CUSTOM_TXT_CDS <CON_TC_SNO104>
J 2
(-2150 2225);
PAINT ORANGE (-2150 2225);
FORCEPROP 1 LAST CUSTOM_TXT_CDS <CON_TC_SNO105>
J 2
(-2150 2125);
PAINT ORANGE (-2150 2125);
FORCEPROP 1 LAST CUSTOM_TXT_CDS <CON_TC_SNO106>
J 2
(-2150 2025);
PAINT ORANGE (-2150 2025);
FORCEPROP 1 LAST CUSTOM_TXT_CDS <CON_TC_SNO107>
J 2
(-2150 1925);
PAINT ORANGE (-2150 1925);
FORCEPROP 1 LAST CUSTOM_TXT_CDS <CON_TC_SNO108>
J 2
(-2150 1825);
PAINT ORANGE (-2150 1825);
FORCEPROP 1 LAST CUSTOM_TXT_CDS <CON_TC_SNO109>
J 2
(-2150 1725);
PAINT ORANGE (-2150 1725);
FORCEPROP 1 LAST CUSTOM_TXT_CDS <CON_TC_SNO110>
J 2
(-2150 1625);
PAINT ORANGE (-2150 1625);
FORCEPROP 1 LAST CUSTOM_TXT_CDS <CON_TC_SNO111>
J 2
(-2150 1525);
PAINT ORANGE (-2150 1525);
FORCEPROP 1 LAST CUSTOM_TXT_CDS <CON_TC_SNO112>
J 2
(-2150 1425);
PAINT ORANGE (-2150 1425);
FORCEPROP 1 LAST CUSTOM_TXT_CDS <CON_TC_SNO113>
J 2
(-2150 1325);
PAINT ORANGE (-2150 1325);
FORCEPROP 1 LAST CUSTOM_TXT_CDS <CON_TC_SNO114>
J 2
(-2150 1225);
PAINT ORANGE (-2150 1225);
FORCEPROP 1 LAST CUSTOM_TXT_CDS <CON_TC_SNO115>
J 2
(-2150 1125);
PAINT ORANGE (-2150 1125);
FORCEPROP 1 LAST CUSTOM_TXT_CDS <CON_TC_SNO116>
J 2
(-2150 1025);
PAINT ORANGE (-2150 1025);
FORCEPROP 1 LAST CUSTOM_TXT_CDS <CON_TC_SNO117>
J 2
(-2150 925);
PAINT ORANGE (-2150 925);
FORCEPROP 1 LAST CUSTOM_TXT_CDS <CON_TC_SNO118>
J 2
(-2150 825);
PAINT ORANGE (-2150 825);
FORCEPROP 1 LAST CUSTOM_TXT_CDS <CON_TC_SNO119>
J 2
(-2150 725);
PAINT ORANGE (-2150 725);
FORCEPROP 1 LAST CUSTOM_TXT_CDS <CON_TC_SNO120>
J 2
(-2150 625);
PAINT ORANGE (-2150 625);
FORCEPROP 1 LAST SCH_TITLE INDEX (3 OF 3)
J 0
(-7950 50);
DISPLAY 1.212766 (-7950 50);
PAINT ORANGE (-7950 50);
FORCEPROP 2 LAST PAGE_BORDER TRUE
J 0
(-7890 5250);
DISPLAY 0.851064 (-7890 5250);
PAINT PINK (-7890 5250);
DISPLAY INVISIBLE (-7890 5250);
FORCEPROP 2 LAST CDS_LIB mstr_symbols
J 0
(0 0);
PAINT ORANGE (0 0);
DISPLAY INVISIBLE (0 0);
FORCEPROP 1 LAST TOC_SYMBOL TRUE
J 0
(-7950 5050);
PAINT ORANGE (-7950 5050);
DISPLAY INVISIBLE (-7950 5050);
FORCEPROP 1 LAST SCH_NUMBER H4694802
J 0
(-1300 150);
DISPLAY 1.212766 (-1300 150);
PAINT YELLOW (-1300 150);
DISPLAY INVISIBLE (-1300 150);
FORCEPROP 1 LAST COMMENT_BODY TRUE
J 0
(12 12);
DISPLAY 0.468085 (12 12);
PAINT GREEN (12 12);
DISPLAY INVISIBLE (12 12);
FORCEPROP 2 LAST CDS_XR_PAGE_TITLE CR-4 : @BASEBOARD_FAB2_LIB.BASEBOARD_FAB2(SCH_1):PAGE4
J 0
(-7890 5250);
DISPLAY 0.638298 (-7890 5250);
PAINT PINK (-7890 5250);
DISPLAY INVISIBLE (-7890 5250);
QUIT
